# ZAIUS-LV CARD-DVT-X01-BOM-X00_20170420_Final.xls.xlsx — TLA (bom)
| FOXCONN TECHNOLOGY GROUP |  |  |  |  |  |  |  |  |  |
| BILL OF MATERIAL |  |  |  |  |  |  |  |  |  |
| AA P/N | 1A42F9300-600-G | CUSTOMER |  | Customer P/N |  | Product Code |  |  |  |
| PWA P/N |  | PWA DESCRIPTION | PCIe LOM+VGA Pass Through card |  |  | PWA REV | X00 X01 | Prepared By SE | 42844 |
| Item | FOXCONN P/N | Customer P/N | Part Description | Manufacturer  Full Name | Manufacturer  Part Number | Qty | RoHS Status | Location | Remark |
| 1 | 7J-004-938 |  | L6 LABEL ( 12.7*11.1mm) | FOXCONN / EPD1 | 7J-004-938 | 1 | G |  |  |
